# BASEBOARD_FAB2 (Tioga Pass) — schematic parts with pin connectivity, parts 2257–2271 of 4751; source: Cadence DE-HDL packaged netlist (pstxprt.dat, pstxnet.dat, pstchip.dat)

EU1A1  IR354XX  IR35411 IC  pkg SM  page 227
  1  VOS  BI  = PVDDQ_KLM
  2  LGND  GROUND  = GND
  3  VCC  POWER  = VR_PVDDQ_KLM_PH2_VCIN
  4  VDRV  BI  = P5V_STBY
  5  PGND(0)  GROUND  = GND
  6  GL(0)  BI  = TP_PVDDQ_KLM_PH2_GL_0
  7  PGND(1)  GROUND  = GND
  10  SW  BI  = VR_PVDDQ_KLM_PH2_SW
  25  VIN(0)  POWER  = VR_FET_SW_P12V_STBY_PVDDQ_KLM
  30  VIN(1)  POWER  = VR_FET_SW_P12V_STBY_PVDDQ_KLM
  31  NC  NC  = NC
  32  PHASE  BI  = VR_PVDDQ_KLM_PH2_PHASE
  33  BOOST  BI  = VR_PVDDQ_KLM_PH2_BOOT_R
  34  PWM  IN  = VR_PVDDQ_KLM_PWM2
  35  EN  BI  = P5V_STBY
  36  TOUT_FLT  BI  = A_TSENSE_PVDDQ_KLM
  37  OCSET  BI  = VR_PVDDQ_KLM_PH2_OCSET
  38  IOUT  OUT  = ISENSE_PVDDQ_KLM_PH2_IMON
  39  REFIN  IN  = VR_PVDDQ_KLM_AIREF2
  40  PGND(2)  GROUND  = GND
  41  GL(1)  BI  = TP_PVDDQ_KLM_PH2_GL_1

EU1A2  IR354XX  IR35411 IC  pkg SM  page 227
  1  VOS  BI  = PVDDQ_KLM
  2  LGND  GROUND  = GND
  3  VCC  POWER  = VR_PVDDQ_KLM_PH1_VCIN
  4  VDRV  BI  = P5V_STBY
  5  PGND(0)  GROUND  = GND
  6  GL(0)  BI  = TP_PVDDQ_KLM_PH1_GL_0
  7  PGND(1)  GROUND  = GND
  10  SW  BI  = VR_PVDDQ_KLM_PH1_SW
  25  VIN(0)  POWER  = VR_FET_SW_P12V_STBY_PVDDQ_KLM
  30  VIN(1)  POWER  = VR_FET_SW_P12V_STBY_PVDDQ_KLM
  31  NC  NC  = NC
  32  PHASE  BI  = VR_PVDDQ_KLM_PH1_PHASE
  33  BOOST  BI  = VR_PVDDQ_KLM_PH1_BOOT_R
  34  PWM  IN  = VR_PVDDQ_KLM_PWM1
  35  EN  BI  = P5V_STBY
  36  TOUT_FLT  BI  = A_TSENSE_PVDDQ_KLM
  37  OCSET  BI  = VR_PVDDQ_KLM_PH1_OCSET
  38  IOUT  OUT  = ISENSE_PVDDQ_KLM_PH1_IMON
  39  REFIN  IN  = VR_PVDDQ_KLM_AIREF1
  40  PGND(2)  GROUND  = GND
  41  GL(1)  BI  = TP_PVDDQ_KLM_PH1_GL_1

EU1B1  PXM1310B  IC  pkg QFN  page 226
  1  BPWM1  OUT  = NC
  2  DNC(0)  NC  = NC
  3  APWM3  OUT  = NC
  4  APWM2  OUT  = VR_PVDDQ_KLM_PWM2
  5  APWM1  OUT  = VR_PVDDQ_KLM_PWM1
  6  SDA  BI  = SMB_VR_STBY_LVC3_SDA
  7  SCL  BI  = SMB_VR_STBY_LVC3_SCL
  8  RESET_N  IN  = NC
  9  AVRRDY  OUT  = PWRGD_PVDDQ_KLM_R
  10  AVREN  IN  = VR_PVDDQ_KLM_VREN
  11  VRHOT_N  OUT  = IRQ_PVDDQ_KLM_VRHOT_LVT3_R_N
  12  PINALRT_N  OUT  = NC
  13  MP0  BI  = PU_VR_PVDDQ_KLM_FAULT1
  14  MP1  BI  = NC_PVDDQ_KLM_GP1
  15  VCLK  IN  = SVID_CLK_PVDDQ_KLM
  16  VDIO  BI  = SVID_VDIO_PVDDQ_KLM
  17  VALRT_N  OUT  = SVID_ALERT_PVDDQ_KLM
  18  MP2  BI  = NC_PVDDQ_KLM_GP0
  19  AVSEN  IN  = VR_PVDDQ_KLM_AVSP
  20  AVREF  IN  = VSENSE_PVDDQ_KLM_N
  21  AIREF1  IN  = VR_PVDDQ_KLM_AIREF1
  22  AISEN1  IN  = ISENSE_PVDDQ_KLM_PH1_IMON
  23  AIREF2  IN  = VR_PVDDQ_KLM_AIREF2
  24  AISEN2  IN  = ISENSE_PVDDQ_KLM_PH2_IMON
  25  AIREF3  IN  = NC
  26  AISEN3  IN  = NC
  27  GND  GROUND  = GND
  28  DNC(1)  NC  = NC
  29  BVSEN  IN  = NC
  30  BVREF  IN  = NC
  31  BIREF1  IN  = NC
  32  BISEN1  IN  = GND
  33  XADDR2  IN  = VR_PVDDQ_KLM_XADDR2
  34  BTSEN  IN  = NC
  35  ATSEN  IN  = A_TSENSE_PVDDQ_KLM
  36  XADDR1  IN  = VR_PVDDQ_KLM_XADDR1
  37  VINSEN  IN  = VR_PVDDQ_KLM_VINSEN
  38  IINSEN  IN  = VR_PVDDQ_KLM_AIINSEN
  39  VDD  POWER  = VR_PVDDQ_KLM_VDD
  40  VD12  BI  = VR_PVDDQ_KLM_VD12
  41  THPAD  GROUND  = GND

EU1C1  IR354XX  IR35412 IC  pkg SM  page 210
  1  VOS  BI  = PVSA_CPU1
  2  LGND  GROUND  = GND
  3  VCC  POWER  = VR_PVSA_CPU1_VCIN
  4  VDRV  BI  = P5V_STBY
  5  PGND(0)  GROUND  = GND
  6  GL(0)  BI  = TP_PVSA_CPU1_GL_0
  7  PGND(1)  GROUND  = GND
  10  SW  BI  = VR_PVSA_CPU1_PHASE_SW
  25  VIN(0)  POWER  = VR_FET_SW_P12V_STBY_PVCCIN_CPU1
  30  VIN(1)  POWER  = VR_FET_SW_P12V_STBY_PVCCIN_CPU1
  31  NC  NC  = NC
  32  PHASE  BI  = VR_PVSA_CPU1_PHASE
  33  BOOST  BI  = VR_PVSA_CPU1_BOOT_R
  34  PWM  IN  = VR_PVSA_CPU1_PWM
  35  EN  BI  = P5V_STBY
  36  TOUT_FLT  BI  = A_TSENSE_PVSA_CPU1
  37  OCSET  BI  = VR_PVSA_CPU1_OCSET
  38  IOUT  OUT  = ISENSE_PVSA_CPU1_IMON
  39  REFIN  IN  = VR_PVSA_CPU1_BIREF1
  40  PGND(2)  GROUND  = GND
  41  GL(1)  BI  = TP_PVSA_CPU1_GL_1

EU1C2  PXE1610B  IC  pkg QFN  page 206
  1  BPWM1  OUT  = VR_PVSA_CPU1_PWM
  2  APWM6  OUT  = NC
  3  APWM5  OUT  = VR_PVCCIN_CPU1_PWM5
  4  APWM4  OUT  = VR_PVCCIN_CPU1_PWM4
  5  APWM3  OUT  = VR_PVCCIN_CPU1_PWM3
  6  APWM2  OUT  = VR_PVCCIN_CPU1_PWM2
  7  APWM1  OUT  = VR_PVCCIN_CPU1_PWM1
  8  SDA  BI  = SMB_VR_STBY_LVC3_SDA
  9  SCL  BI  = SMB_VR_STBY_LVC3_SCL
  10  RESET_N  IN  = NC
  11  AVRRDY  OUT  = VR_VRRDY_PVCCIN_CPU1
  12  AVREN  IN  = VR_PVCCIN_CPU1_VREN
  13  VRHOT_N  OUT  = IRQ_PVCCIN_CPU1_VRHOT_LVC3_R_N
  14  PINALRT_N  OUT  = FM_PVCCIN_CPU1_PWR_IN_ALERT_N
  15  MP0  BI  = PWRGD_PVSA_CPU1_R
  16  MP1  BI  = NC
  17  VCLK  IN  = SVID_VCLK_PVCCIN_CPU1
  18  VDIO  BI  = SVID_VDIO_PVCCIN_CPU1
  19  VALRT_N  OUT  = SVID_VALERT_VCCIN_CPU1
  20  MP2  OUT  = PU_VR_PVCCIN_CPU1_FLT1_SMBALT_N
  21  AVSEN  IN  = VSENSE_PVCCIN_CPU1_AVSP
  22  AVREF  IN  = VSENSE_PVCCIN_CPU1_N
  23  AIREF1  IN  = VR_PVCCIN_CPU1_AIREF1
  24  AISEN1  IN  = ISENSE_PVCCIN_CPU1_PH1_IMON
  25  AIREF2  IN  = VR_PVCCIN_CPU1_AIREF2
  26  AISEN2  IN  = ISENSE_PVCCIN_CPU1_PH2_IMON
  27  AIREF3  IN  = VR_PVCCIN_CPU1_AIREF3
  28  AISEN3  IN  = ISENSE_PVCCIN_CPU1_PH3_IMON
  29  AIREF4  IN  = VR_PVCCIN_CPU1_AIREF4
  30  AISEN4  IN  = ISENSE_PVCCIN_CPU1_PH4_IMON
  31  AIREF5  IN  = VR_PVCCIN_CPU1_AIREF5
  32  AISEN5  IN  = ISENSE_PVCCIN_CPU1_PH5_IMON
  33  AIREF6  IN  = NC
  34  AISEN6  IN  = NC
  35  BVSEN  IN  = VSENSE_PVSA_CPU1_BVSP
  36  BVREF  IN  = VSENSE_PVSA_CPU1_N
  37  BIREF1  IN  = VR_PVSA_CPU1_BIREF1
  38  BISEN1  IN  = ISENSE_PVSA_CPU1_IMON
  39  MP3  OUT  = PU_VR_PVCCIN_CPU1_IMON
  40  MP4  OUT  = NC
  41  XADDR2  IN  = VR_PVCCIN_CPU1_XADDR2
  42  BTSEN  IN  = A_TSENSE_PVSA_CPU1
  43  ATSEN  IN  = A_TSENSE_PVCCIN_CPU1
  44  XADDR1  IN  = VR_PVCCIN_CPU1_XADDR1
  45  VINSEN  IN  = VR_PVCCIN_CPU1_AVINSEN
  46  IINSEN  IN  = NC
  47  VDD  POWER  = VR_PVCCIN_CPU1_VDD
  48  VD12  POWER  = VR_PVCCIN_CPU1_VD12
  49  THPAD  GROUND  = GND

EU1C3  IR354XX  IR35411 IC  pkg SM  page 209
  1  VOS  BI  = PVCCIN_CPU1
  2  LGND  GROUND  = GND
  3  VCC  POWER  = VR_PVCCIN_CPU1_PH5_VCIN
  4  VDRV  BI  = P5V_STBY
  5  PGND(0)  GROUND  = GND
  6  GL(0)  BI  = TP_PVCCIN_CPU1_PH5_GL_0
  7  PGND(1)  GROUND  = GND
  10  SW  BI  = VR_PVCCIN_CPU1_PHASE5
  25  VIN(0)  POWER  = VR_FET_SW_P12V_STBY_PVCCIN_CPU1
  30  VIN(1)  POWER  = VR_FET_SW_P12V_STBY_PVCCIN_CPU1
  31  NC  NC  = NC
  32  PHASE  BI  = VR_PVCCIN_CPU1_PH5_PHASE
  33  BOOST  BI  = VR_PVCCIN_CPU1_PH5_BOOT_R
  34  PWM  IN  = VR_PVCCIN_CPU1_PWM5
  35  EN  BI  = P5V_STBY
  36  TOUT_FLT  BI  = A_TSENSE_PVCCIN_CPU1
  37  OCSET  BI  = VR_PVCCIN_CPU1_PH5_OCSET
  38  IOUT  OUT  = ISENSE_PVCCIN_CPU1_PH5_IMON
  39  REFIN  IN  = VR_PVCCIN_CPU1_AIREF5
  40  PGND(2)  GROUND  = GND
  41  GL(1)  BI  = TP_PVCCIN_CPU1_PH5_GL_1

EU1D1  IR354XX  IR35411 IC  pkg SM  page 208
  1  VOS  BI  = PVCCIN_CPU1
  2  LGND  GROUND  = GND
  3  VCC  POWER  = VR_PVCCIN_CPU1_PH4_VCIN
  4  VDRV  BI  = P5V_STBY
  5  PGND(0)  GROUND  = GND
  6  GL(0)  BI  = TP_PVCCIN_CPU1_PH4_GL_0
  7  PGND(1)  GROUND  = GND
  10  SW  BI  = VR_PVCCIN_CPU1_PHASE4
  25  VIN(0)  POWER  = VR_FET_SW_P12V_STBY_PVCCIN_CPU1
  30  VIN(1)  POWER  = VR_FET_SW_P12V_STBY_PVCCIN_CPU1
  31  NC  NC  = NC
  32  PHASE  BI  = VR_PVCCIN_CPU1_PH4_PHASE
  33  BOOST  BI  = VR_PVCCIN_CPU1_PH4_BOOT_R
  34  PWM  IN  = VR_PVCCIN_CPU1_PWM4
  35  EN  BI  = P5V_STBY
  36  TOUT_FLT  BI  = A_TSENSE_PVCCIN_CPU1
  37  OCSET  BI  = VR_PVCCIN_CPU1_PH4_OCSET
  38  IOUT  OUT  = ISENSE_PVCCIN_CPU1_PH4_IMON
  39  REFIN  IN  = VR_PVCCIN_CPU1_AIREF4
  40  PGND(2)  GROUND  = GND
  41  GL(1)  BI  = TP_PVCCIN_CPU1_PH4_GL_1

EU1D2  ADM1278  IC  pkg SM  page 199
  1  PSET  IN  = A_HSC_PSET
  2  VCAP  IN  = A_HSC_VCAP
  3  ISET  IN  = A_HSC_ISET
  4  ISTART  IN  = A_HSC_ISTART
  5  TIMER  UNSPEC  = A_HSC_TIMER
  6  FAULT_N  UNSPEC  = IRQ_HSC_FAULT_R_N
  7  ADR1  UNSPEC  = FM_P12V_HSC_ADR1
  8  ADR2  UNSPEC  = FM_P12V_HSC_ADR2
  9  SPISS_N  UNSPEC  = TP_HSC_SPISSN
  10  MCLK  OUT  = TP_HSC_MCLK
  11  MDAT  OUT  = TP_HSC_MDAT
  12  ENABLE  IN  = FM_P12V_HOTSWAP0_EN
  13  GPO1_ALERT1_N_CONV  BI  = IRQ_SML1_PMBUS_ALERT_R_N
  14  GPO2_ALERT2_N  BI  = TP_HSC_ALERT2_N
  15  SDA  BI  = SMB_3V3SB_HSC_SDA_R
  16  SCL  IN  = SMB_3V3SB_HSC_SCL_R
  17  RETRY_N  UNSPEC  = PD_HSC_RETRY_N
  18  PWRGD  UNSPEC  = PWRGD_P12V_R
  19  CSOUT  OUT  = A_HSC_CSOUT
  20  VOUT  OUT  = A_HSC_VOUT
  21  PWGIN  IN  = A_HSC_PWGIN
  22  GND  GROUND  = AGND_HSC
  23  PGND  GROUND  = GND
  24  GATE  OUT  = A_HSC_GATE
  25  TEMP  IN  = A_HSC_TEMP
  26  MON  IN  = A_HSC_MON
  27  HSN  IN  = A_HSC_HSN
  28  HSP  IN  = A_HSC_HSP
  29  MOP  IN  = A_HSC_MOP
  30  VCC  POWER  = P12V_HSC_VCC
  31  UV  IN  = A_HSC_UV
  32  OV  IN  = A_HSC_OV
  33  EP  GROUND  = AGND_HSC

EU1D3  IR354XX  IR35411 IC  pkg SM  page 208
  1  VOS  BI  = PVCCIN_CPU1
  2  LGND  GROUND  = GND
  3  VCC  POWER  = VR_PVCCIN_CPU1_PH3_VCIN
  4  VDRV  BI  = P5V_STBY
  5  PGND(0)  GROUND  = GND
  6  GL(0)  BI  = TP_PVCCIN_CPU1_PH3_GL_0
  7  PGND(1)  GROUND  = GND
  10  SW  BI  = VR_PVCCIN_CPU1_PHASE3
  25  VIN(0)  POWER  = VR_FET_SW_P12V_STBY_PVCCIN_CPU1
  30  VIN(1)  POWER  = VR_FET_SW_P12V_STBY_PVCCIN_CPU1
  31  NC  NC  = NC
  32  PHASE  BI  = VR_PVCCIN_CPU1_PH3_PHASE
  33  BOOST  BI  = VR_PVCCIN_CPU1_PH3_BOOT_R
  34  PWM  IN  = VR_PVCCIN_CPU1_PWM3
  35  EN  BI  = P5V_STBY
  36  TOUT_FLT  BI  = A_TSENSE_PVCCIN_CPU1
  37  OCSET  BI  = VR_PVCCIN_CPU1_PH3_OCSET
  38  IOUT  OUT  = ISENSE_PVCCIN_CPU1_PH3_IMON
  39  REFIN  IN  = VR_PVCCIN_CPU1_AIREF3
  40  PGND(2)  GROUND  = GND
  41  GL(1)  BI  = TP_PVCCIN_CPU1_PH3_GL_1

EU1D4  IR354XX  IR35411 IC  pkg SM  page 207
  1  VOS  BI  = PVCCIN_CPU1
  2  LGND  GROUND  = GND
  3  VCC  POWER  = VR_PVCCIN_CPU1_PH2_VCIN
  4  VDRV  BI  = P5V_STBY
  5  PGND(0)  GROUND  = GND
  6  GL(0)  BI  = TP_PVCCINC_CPU1_PH2_GL_0
  7  PGND(1)  GROUND  = GND
  10  SW  BI  = VR_PVCCIN_CPU1_PHASE2
  25  VIN(0)  POWER  = VR_FET_SW_P12V_STBY_PVCCIN_CPU1
  30  VIN(1)  POWER  = VR_FET_SW_P12V_STBY_PVCCIN_CPU1
  31  NC  NC  = NC
  32  PHASE  BI  = VR_PVCCIN_CPU1_PH2_PHASE
  33  BOOST  BI  = VR_PVCCIN_CPU1_PH2_BOOT_R
  34  PWM  IN  = VR_PVCCIN_CPU1_PWM2
  35  EN  BI  = P5V_STBY
  36  TOUT_FLT  BI  = A_TSENSE_PVCCIN_CPU1
  37  OCSET  BI  = VR_PVCCIN_CPU1_PH2_OCSET
  38  IOUT  OUT  = ISENSE_PVCCIN_CPU1_PH2_IMON
  39  REFIN  IN  = VR_PVCCIN_CPU1_AIREF2
  40  PGND(2)  GROUND  = GND
  41  GL(1)  BI  = TP_PVCCINC_CPU1_PH2_GL_1

EU1E1  MOSFETN_1D3S  IC  pkg SOT5  page 200
  1  S1  UNSPEC  = P12V_STBY
  2  S2  UNSPEC  = P12V_STBY
  3  S3  UNSPEC  = P12V_STBY
  4  G  IN  = A_HSC_GATE3_R
  5  D  UNSPEC  = P12V_MB0_SW

EU1E2  IR354XX  IR35411 IC  pkg SM  page 207
  1  VOS  BI  = PVCCIN_CPU1
  2  LGND  GROUND  = GND
  3  VCC  POWER  = VR_PVCCIN_CPU1_PH1_VCIN
  4  VDRV  BI  = P5V_STBY
  5  PGND(0)  GROUND  = GND
  6  GL(0)  BI  = TP_PVCCINC_CPU1_PH1_GL_0
  7  PGND(1)  GROUND  = GND
  10  SW  BI  = VR_PVCCIN_CPU1_PHASE1
  25  VIN(0)  POWER  = VR_FET_SW_P12V_STBY_PVCCIN_CPU1
  30  VIN(1)  POWER  = VR_FET_SW_P12V_STBY_PVCCIN_CPU1
  31  NC  NC  = NC
  32  PHASE  BI  = VR_PVCCIN_CPU1_PH1_PHASE
  33  BOOST  BI  = VR_PVCCIN_CPU1_PH1_BOOT_R
  34  PWM  IN  = VR_PVCCIN_CPU1_PWM1
  35  EN  BI  = P5V_STBY
  36  TOUT_FLT  BI  = A_TSENSE_PVCCIN_CPU1
  37  OCSET  BI  = VR_PVCCIN_CPU1_PH1_OCSET
  38  IOUT  OUT  = ISENSE_PVCCIN_CPU1_PH1_IMON
  39  REFIN  IN  = VR_PVCCIN_CPU1_AIREF1
  40  PGND(2)  GROUND  = GND
  41  GL(1)  BI  = TP_PVCCINC_CPU1_PH1_GL_1

EU1E3  MOSFETN_1D3S  IC  pkg SOT5  page 200
  1  S1  UNSPEC  = P12V_STBY
  2  S2  UNSPEC  = P12V_STBY
  3  S3  UNSPEC  = P12V_STBY
  4  G  IN  = A_HSC_GATE1_R
  5  D  UNSPEC  = P12V_MB0_SW

EU1F1  IR354XX  IR35411 IC  pkg SM  page 224
  1  VOS  BI  = PVDDQ_GHJ
  2  LGND  GROUND  = GND
  3  VCC  POWER  = VR_PVDDQ_GHJ_PH2_VCIN
  4  VDRV  BI  = P5V_STBY
  5  PGND(0)  GROUND  = GND
  6  GL(0)  BI  = TP_PVDDQ_GHJ_PH2_GL_0
  7  PGND(1)  GROUND  = GND
  10  SW  BI  = VR_PVDDQ_GHJ_PH2_SW
  25  VIN(0)  POWER  = VR_FET_SW_P12V_STBY_PVDDQ_GHJ
  30  VIN(1)  POWER  = VR_FET_SW_P12V_STBY_PVDDQ_GHJ
  31  NC  NC  = NC
  32  PHASE  BI  = VR_PVDDQ_GHJ_PH2_PHASE
  33  BOOST  BI  = VR_PVDDQ_GHJ_PH2_BOOT_R
  34  PWM  IN  = VR_PVDDQ_GHJ_PWM2
  35  EN  BI  = P5V_STBY
  36  TOUT_FLT  BI  = A_TSENSE_PVDDQ_GHJ
  37  OCSET  BI  = VR_PVDDQ_GHJ_PH2_OCSET
  38  IOUT  OUT  = ISENSE_PVDDQ_GHJ_PH2_IMON
  39  REFIN  IN  = VR_PVDDQ_GHJ_AIREF2
  40  PGND(2)  GROUND  = GND
  41  GL(1)  BI  = TP_PVDDQ_GHJ_PH2_GL_1

EU1G1  IR354XX  IR35411 IC  pkg SM  page 224
  1  VOS  BI  = PVDDQ_GHJ
  2  LGND  GROUND  = GND
  3  VCC  POWER  = VR_PVDDQ_GHJ_PH1_VCIN
  4  VDRV  BI  = P5V_STBY
  5  PGND(0)  GROUND  = GND
  6  GL(0)  BI  = TP_PVDDQ_GHJ_PH1_GL_0
  7  PGND(1)  GROUND  = GND
  10  SW  BI  = VR_PVDDQ_GHJ_PH1_SW
  25  VIN(0)  POWER  = VR_FET_SW_P12V_STBY_PVDDQ_GHJ
  30  VIN(1)  POWER  = VR_FET_SW_P12V_STBY_PVDDQ_GHJ
  31  NC  NC  = NC
  32  PHASE  BI  = VR_PVDDQ_GHJ_PH1_PHASE
  33  BOOST  BI  = VR_PVDDQ_GHJ_PH1_BOOT_R
  34  PWM  IN  = VR_PVDDQ_GHJ_PWM1
  35  EN  BI  = P5V_STBY
  36  TOUT_FLT  BI  = A_TSENSE_PVDDQ_GHJ
  37  OCSET  BI  = VR_PVDDQ_GHJ_PH1_OCSET
  38  IOUT  OUT  = ISENSE_PVDDQ_GHJ_PH1_IMON
  39  REFIN  IN  = VR_PVDDQ_GHJ_AIREF1
  40  PGND(2)  GROUND  = GND
  41  GL(1)  BI  = TP_PVDDQ_GHJ_PH1_GL_1
